# T6G (Grand Teton) — schematic netlist excerpt (pin names and nets, part order shuffled) for the footprints in the layout excerpt that follows; sources: Cadence DE-HDL packaged netlist, KiCad conversion of 04192023_DAF0TMB3IC0_F0TG_MB_C_brd_V02_OCP.brd

Q129  MOSFET_NCH_DUAL  PJT138K IC  pkg SOT363XD  page 125
  S1  = GND
  G1  = GPU_3V3IO_RSVD5_FFU
  D2  = GPU_3V3IO_RSVD5_FFU_ISO
  S2  = GND
  G2  = GPU_3V3IO_RSVD5_FFU_N
  D1  = GPU_3V3IO_RSVD5_FFU_N

R988  Q_RES  0 5% EMPTY  pkg 0402LF  page 159 : A = I3C_0_SPD_DDRAF_CPU1_R_SCL ; B = I3C_SPD_DDRAF_CPU1_BYPASS_SCL

(kicad_pcb
	(version 20260206)
	(generator "pcbnew")
	(generator_version "10.0")
	(general
		(thickness 1.6)
		(legacy_teardrops no)
	)
	(paper "A4")
	(title_block
		(title "04192023_DAF0TMB3IC0_F0TG_MB_C_brd_V02_OCP.brd")
		(comment 1 "Grand Teton / footprints 2594-2595 of 8354")
	)
	(layers
		(0 "F.Cu" signal "TOP")
		(4 "In1.Cu" signal "GND")
		(6 "In2.Cu" signal "IN1")
		(8 "In3.Cu" signal "GND1")
		(10 "In4.Cu" signal "IN2")
		(12 "In5.Cu" signal "GND2")
		(14 "In6.Cu" signal "IN3")
		(16 "In7.Cu" signal "GND3")
		(18 "In8.Cu" signal "VCC")
		(20 "In9.Cu" signal "VCC1")
		(22 "In10.Cu" signal "GND4")
		(24 "In11.Cu" signal "IN4")
		(26 "In12.Cu" signal "GND5")
		(28 "In13.Cu" signal "IN5")
		(30 "In14.Cu" signal "GND6")
		(32 "In15.Cu" signal "IN6")
		(34 "In16.Cu" signal "GND7")
		(2 "B.Cu" signal "BOTTOM")
		(9 "F.Adhes" user "F.Adhesive")
		(11 "B.Adhes" user "B.Adhesive")
		(13 "F.Paste" user "Package Geometry/Pastemask Top")
		(15 "B.Paste" user "Package Geometry/Pastemask Bottom")
		(5 "F.SilkS" user "Ref Des/Silkscreen Top")
		(7 "B.SilkS" user "Ref Des/Silkscreen Bottom")
		(1 "F.Mask" user "Board Geometry/Soldermask Top")
		(3 "B.Mask" user "Board Geometry/Soldermask Bottom")
		(17 "Dwgs.User" user "User.Drawings")
		(19 "Cmts.User" user "User.Comments")
		(21 "Eco1.User" user "User.Eco1")
		(23 "Eco2.User" user "User.Eco2")
		(25 "Edge.Cuts" user "Board Geometry/Outline")
		(27 "Margin" user)
		(31 "F.CrtYd" user "Package Geometry/Place Bound Top")
		(29 "B.CrtYd" user "Package Geometry/Place Bound Bottom")
		(35 "F.Fab" user "Ref Des/Assembly Top")
		(33 "B.Fab" user "Ref Des/Assembly Bottom")
	)
	(footprint ""
		(layer "F.Cu")
		(at 43.4721 -170.307)
		(property "Reference" "R988"
			(at 0 0 0)
			(layer "F.SilkS")
			(hide yes)
			(effects
				(font
					(size 1.27 1.27)
				)
			)
		)
		(property "Value" ""
			(at 0 0 0)
			(layer "F.Fab")
			(effects
				(font
					(size 1.27 1.27)
				)
			)
		)
		(duplicate_pad_numbers_are_jumpers no)
		(fp_line
			(start -0.7874 -0.4064)
			(end 0.7874 -0.4064)
			(stroke
				(width 0.1524)
				(type default)
			)
			(layer "F.SilkS")
		)
		(fp_line
			(start -0.7874 0.4064)
			(end -0.7874 -0.4064)
			(stroke
				(width 0.1524)
				(type default)
			)
			(layer "F.SilkS")
		)
		(fp_line
			(start 0.7874 -0.4064)
			(end 0.7874 0.4064)
			(stroke
				(width 0.1524)
				(type default)
			)
			(layer "F.SilkS")
		)
		(fp_line
			(start 0.7874 0.4064)
			(end -0.7874 0.4064)
			(stroke
				(width 0.1524)
				(type default)
			)
			(layer "F.SilkS")
		)
		(fp_line
			(start -0.67945 -0.305054)
			(end -0.12065 -0.305054)
			(stroke
				(width 0.1)
				(type default)
			)
			(layer "F.Fab")
		)
		(fp_line
			(start -0.67945 0.3048)
			(end -0.67945 -0.305054)
			(stroke
				(width 0.1)
				(type default)
			)
			(layer "F.Fab")
		)
		(fp_line
			(start -0.12065 -0.305054)
			(end -0.12065 -0.2794)
			(stroke
				(width 0.1)
				(type default)
			)
			(layer "F.Fab")
		)
		(fp_line
			(start -0.12065 -0.2794)
			(end 0.12065 -0.2794)
			(stroke
				(width 0.1)
				(type default)
			)
			(layer "F.Fab")
		)
		(fp_line
			(start -0.12065 0.2794)
			(end -0.12065 0.3048)
			(stroke
				(width 0.1)
				(type default)
			)
			(layer "F.Fab")
		)
		(fp_line
			(start -0.12065 0.3048)
			(end -0.67945 0.3048)
			(stroke
				(width 0.1)
				(type default)
			)
			(layer "F.Fab")
		)
		(fp_line
			(start 0.120396 0.2794)
			(end -0.12065 0.2794)
			(stroke
				(width 0.1)
				(type default)
			)
			(layer "F.Fab")
		)
		(fp_line
			(start 0.120396 0.3048)
			(end 0.120396 0.2794)
			(stroke
				(width 0.1)
				(type default)
			)
			(layer "F.Fab")
		)
		(fp_line
			(start 0.12065 -0.3048)
			(end 0.67945 -0.3048)
			(stroke
				(width 0.1)
				(type default)
			)
			(layer "F.Fab")
		)
		(fp_line
			(start 0.12065 -0.2794)
			(end 0.12065 -0.3048)
			(stroke
				(width 0.1)
				(type default)
			)
			(layer "F.Fab")
		)
		(fp_line
			(start 0.67945 -0.3048)
			(end 0.67945 0.3048)
			(stroke
				(width 0.1)
				(type default)
			)
			(layer "F.Fab")
		)
		(fp_line
			(start 0.67945 0.3048)
			(end 0.120396 0.3048)
			(stroke
				(width 0.1)
				(type default)
			)
			(layer "F.Fab")
		)
		(pad "1" smd rect
			(at -0.40005 0 180)
			(size 0.4572 0.508)
			(layers "F.Cu" "F.Mask" "F.Paste")
			(net "I3C_0_SPD_DDRAF_CPU1_R_SCL")
		)
		(pad "2" smd rect
			(at 0.40005 0 180)
			(size 0.4572 0.508)
			(layers "F.Cu" "F.Mask" "F.Paste")
			(net "I3C_SPD_DDRAF_CPU1_BYPASS_SCL")
		)
	)
	(footprint ""
		(layer "F.Cu")
		(at 304.305716 -437.820308 180)
		(property "Reference" "Q129"
			(at 1.52908 -1.79832 0)
			(unlocked yes)
			(layer "F.SilkS")
			(effects
				(font
					(size 0.7874 0.5842)
					(thickness 0.1524)
				)
				(justify left)
			)
		)
		(property "Value" ""
			(at 0 0 180)
			(layer "F.Fab")
			(effects
				(font
					(size 1.27 1.27)
				)
			)
		)
		(duplicate_pad_numbers_are_jumpers no)
		(fp_line
			(start 1.332738 1.100074)
			(end -1.332738 1.100074)
			(stroke
				(width 0.1524)
				(type default)
			)
			(layer "F.SilkS")
		)
		(fp_line
			(start 1.332738 -1.100074)
			(end 1.332738 1.100074)
			(stroke
				(width 0.1524)
				(type default)
			)
			(layer "F.SilkS")
		)
		(fp_line
			(start 0.4826 -1.100074)
			(end 1.332738 -1.100074)
			(stroke
				(width 0.1524)
				(type default)
			)
			(layer "F.SilkS")
		)
		(fp_line
			(start 0 -0.541274)
			(end 0.4826 -1.100074)
			(stroke
				(width 0.1524)
				(type default)
			)
			(layer "F.SilkS")
		)
		(fp_line
			(start -0.4826 -1.100074)
			(end 0 -0.541274)
			(stroke
				(width 0.1524)
				(type default)
			)
			(layer "F.SilkS")
		)
		(fp_line
			(start -1.332738 1.100074)
			(end -1.332738 -1.100074)
			(stroke
				(width 0.1524)
				(type default)
			)
			(layer "F.SilkS")
		)
		(fp_line
			(start -1.332738 -1.100074)
			(end -0.4826 -1.100074)
			(stroke
				(width 0.1524)
				(type default)
			)
			(layer "F.SilkS")
		)
		(fp_poly
			(pts
				(xy -1.489456 -1.189482) (xy -2.23393 -1.43764) (xy -1.737614 -1.933956)
			)
			(stroke
				(width 0)
				(type default)
			)
			(fill yes)
			(layer "F.SilkS")
		)
		(fp_line
			(start 0.674878 1.100074)
			(end -0.674878 1.100074)
			(stroke
				(width 0.1)
				(type default)
			)
			(layer "F.Fab")
		)
		(fp_line
			(start 0.674878 -1.100074)
			(end 0.674878 1.100074)
			(stroke
				(width 0.1)
				(type default)
			)
			(layer "F.Fab")
		)
		(fp_line
			(start -0.674878 1.100074)
			(end -0.674878 -1.100074)
			(stroke
				(width 0.1)
				(type default)
			)
			(layer "F.Fab")
		)
		(fp_line
			(start -0.674878 -1.100074)
			(end 0.674878 -1.100074)
			(stroke
				(width 0.1)
				(type default)
			)
			(layer "F.Fab")
		)
		(fp_poly
			(pts
				(xy -2.2352 -0.298958) (xy -2.2352 -1.001014) (xy -1.533144 -0.649986)
			)
			(stroke
				(width 0)
				(type default)
			)
			(fill yes)
			(layer "F.Fab")
		)
		(pad "1" smd rect
			(at -0.94996 -0.649986 270)
			(size 0.4318 0.508)
			(layers "F.Cu" "F.Mask" "F.Paste")
			(net "GND")
		)
		(pad "2" smd rect
			(at -0.94996 0 270)
			(size 0.4318 0.508)
			(layers "F.Cu" "F.Mask" "F.Paste")
			(net "GPU_3V3IO_RSVD5_FFU")
		)
		(pad "3" smd rect
			(at -0.94996 0.649986 270)
			(size 0.4318 0.508)
			(layers "F.Cu" "F.Mask" "F.Paste")
			(net "GPU_3V3IO_RSVD5_FFU_ISO")
		)
		(pad "4" smd rect
			(at 0.94996 0.649986 270)
			(size 0.4318 0.508)
			(layers "F.Cu" "F.Mask" "F.Paste")
			(net "GND")
		)
		(pad "5" smd rect
			(at 0.94996 0 270)
			(size 0.4318 0.508)
			(layers "F.Cu" "F.Mask" "F.Paste")
			(net "GPU_3V3IO_RSVD5_FFU_N")
		)
		(pad "6" smd rect
			(at 0.94996 -0.649986 270)
			(size 0.4318 0.508)
			(layers "F.Cu" "F.Mask" "F.Paste")
			(net "GPU_3V3IO_RSVD5_FFU_N")
		)
	)
)
